# SCM (Grand Teton) — schematic netlist excerpt (pin names and nets, part order shuffled) for the footprints in the layout excerpt that follows; sources: Cadence DE-HDL packaged netlist, KiCad conversion of 12092022_DA0F0TMDCD0_F0T_Management_Board_D_brd_V3_OCP.brd

R277  Q_RES  0 5% CHIP  pkg 0402LF  page 56 : A = PWRGD_P1V0_AUX_R ; B = PWRGD_P1V0_AUX
C38  Q_CAP  1UF 25V 10% X6S  pkg C0402  page 15 : A = P3V3_P1V8_SD2VDD ; B = GND

(kicad_pcb
	(version 20260206)
	(generator "pcbnew")
	(generator_version "10.0")
	(general
		(thickness 1.6)
		(legacy_teardrops no)
	)
	(paper "A4")
	(title_block
		(title "12092022_DA0F0TMDCD0_F0T_Management_Board_D_brd_V3_OCP.brd")
		(comment 1 "Grand Teton / footprints 305-306 of 1440")
	)
	(layers
		(0 "F.Cu" signal "TOP")
		(4 "In1.Cu" signal "GND")
		(6 "In2.Cu" signal "IN1")
		(8 "In3.Cu" signal "GND1")
		(10 "In4.Cu" signal "IN2")
		(12 "In5.Cu" signal "VCC")
		(14 "In6.Cu" signal "VCC1")
		(16 "In7.Cu" signal "IN3")
		(18 "In8.Cu" signal "GND2")
		(20 "In9.Cu" signal "IN4")
		(22 "In10.Cu" signal "GND3")
		(2 "B.Cu" signal "BOTTOM")
		(9 "F.Adhes" user "F.Adhesive")
		(11 "B.Adhes" user "B.Adhesive")
		(13 "F.Paste" user "Package Geometry/Pastemask Top")
		(15 "B.Paste" user "Package Geometry/Pastemask Bottom")
		(5 "F.SilkS" user "Ref Des/Silkscreen Top")
		(7 "B.SilkS" user "Ref Des/Silkscreen Bottom")
		(1 "F.Mask" user "Board Geometry/Soldermask Top")
		(3 "B.Mask" user "Board Geometry/Soldermask Bottom")
		(17 "Dwgs.User" user "User.Drawings")
		(19 "Cmts.User" user "User.Comments")
		(21 "Eco1.User" user "User.Eco1")
		(23 "Eco2.User" user "User.Eco2")
		(25 "Edge.Cuts" user "Board Geometry/Outline")
		(27 "Margin" user)
		(31 "F.CrtYd" user "Package Geometry/Place Bound Top")
		(29 "B.CrtYd" user "Package Geometry/Place Bound Bottom")
		(35 "F.Fab" user "Ref Des/Assembly Top")
		(33 "B.Fab" user "Ref Des/Assembly Bottom")
	)
	(footprint ""
		(layer "F.Cu")
		(at 40.41648 -30.63748 -90)
		(property "Reference" "C38"
			(at 0 0 270)
			(layer "F.SilkS")
			(hide yes)
			(effects
				(font
					(size 1.27 1.27)
				)
			)
		)
		(property "Value" ""
			(at 0 0 270)
			(layer "F.Fab")
			(effects
				(font
					(size 1.27 1.27)
				)
			)
		)
		(duplicate_pad_numbers_are_jumpers no)
		(fp_line
			(start -0.7874 0.4064)
			(end -0.7874 -0.4064)
			(stroke
				(width 0.1524)
				(type default)
			)
			(layer "F.SilkS")
		)
		(fp_line
			(start 0.7874 0.4064)
			(end -0.7874 0.4064)
			(stroke
				(width 0.1524)
				(type default)
			)
			(layer "F.SilkS")
		)
		(fp_line
			(start -0.7874 -0.4064)
			(end 0.7874 -0.4064)
			(stroke
				(width 0.1524)
				(type default)
			)
			(layer "F.SilkS")
		)
		(fp_line
			(start 0.7874 -0.4064)
			(end 0.7874 0.4064)
			(stroke
				(width 0.1524)
				(type default)
			)
			(layer "F.SilkS")
		)
		(fp_line
			(start -0.67945 0.3048)
			(end -0.67945 -0.305054)
			(stroke
				(width 0.1)
				(type default)
			)
			(layer "F.Fab")
		)
		(fp_line
			(start -0.12065 0.3048)
			(end -0.67945 0.3048)
			(stroke
				(width 0.1)
				(type default)
			)
			(layer "F.Fab")
		)
		(fp_line
			(start 0.120396 0.3048)
			(end 0.120396 0.2794)
			(stroke
				(width 0.1)
				(type default)
			)
			(layer "F.Fab")
		)
		(fp_line
			(start 0.67945 0.3048)
			(end 0.120396 0.3048)
			(stroke
				(width 0.1)
				(type default)
			)
			(layer "F.Fab")
		)
		(fp_line
			(start -0.12065 0.2794)
			(end -0.12065 0.3048)
			(stroke
				(width 0.1)
				(type default)
			)
			(layer "F.Fab")
		)
		(fp_line
			(start 0.120396 0.2794)
			(end -0.12065 0.2794)
			(stroke
				(width 0.1)
				(type default)
			)
			(layer "F.Fab")
		)
		(fp_line
			(start -0.12065 -0.2794)
			(end 0.12065 -0.2794)
			(stroke
				(width 0.1)
				(type default)
			)
			(layer "F.Fab")
		)
		(fp_line
			(start 0.12065 -0.2794)
			(end 0.12065 -0.3048)
			(stroke
				(width 0.1)
				(type default)
			)
			(layer "F.Fab")
		)
		(fp_line
			(start 0.12065 -0.3048)
			(end 0.67945 -0.3048)
			(stroke
				(width 0.1)
				(type default)
			)
			(layer "F.Fab")
		)
		(fp_line
			(start 0.67945 -0.3048)
			(end 0.67945 0.3048)
			(stroke
				(width 0.1)
				(type default)
			)
			(layer "F.Fab")
		)
		(fp_line
			(start -0.67945 -0.305054)
			(end -0.12065 -0.305054)
			(stroke
				(width 0.1)
				(type default)
			)
			(layer "F.Fab")
		)
		(fp_line
			(start -0.12065 -0.305054)
			(end -0.12065 -0.2794)
			(stroke
				(width 0.1)
				(type default)
			)
			(layer "F.Fab")
		)
		(pad "1" smd circle
			(at -0.40005 0 270)
			(size 0 0)
			(layers "F.Cu" "F.Mask" "F.Paste")
			(net "P3V3_P1V8_SD2VDD")
		)
		(pad "2" smd circle
			(at 0.40005 0 270)
			(size 0 0)
			(layers "F.Cu" "F.Mask" "F.Paste")
			(net "GND")
		)
	)
	(footprint ""
		(layer "F.Cu")
		(at 25.5016 -33.909 90)
		(property "Reference" "R277"
			(at 0 0 90)
			(layer "F.SilkS")
			(hide yes)
			(effects
				(font
					(size 1.27 1.27)
				)
			)
		)
		(property "Value" ""
			(at 0 0 90)
			(layer "F.Fab")
			(effects
				(font
					(size 1.27 1.27)
				)
			)
		)
		(duplicate_pad_numbers_are_jumpers no)
		(fp_line
			(start 0.7874 -0.4064)
			(end 0.7874 0.4064)
			(stroke
				(width 0.1524)
				(type default)
			)
			(layer "F.SilkS")
		)
		(fp_line
			(start -0.7874 -0.4064)
			(end 0.7874 -0.4064)
			(stroke
				(width 0.1524)
				(type default)
			)
			(layer "F.SilkS")
		)
		(fp_line
			(start 0.7874 0.4064)
			(end -0.7874 0.4064)
			(stroke
				(width 0.1524)
				(type default)
			)
			(layer "F.SilkS")
		)
		(fp_line
			(start -0.7874 0.4064)
			(end -0.7874 -0.4064)
			(stroke
				(width 0.1524)
				(type default)
			)
			(layer "F.SilkS")
		)
		(fp_line
			(start -0.12065 -0.305054)
			(end -0.12065 -0.2794)
			(stroke
				(width 0.1)
				(type default)
			)
			(layer "F.Fab")
		)
		(fp_line
			(start -0.67945 -0.305054)
			(end -0.12065 -0.305054)
			(stroke
				(width 0.1)
				(type default)
			)
			(layer "F.Fab")
		)
		(fp_line
			(start 0.67945 -0.3048)
			(end 0.67945 0.3048)
			(stroke
				(width 0.1)
				(type default)
			)
			(layer "F.Fab")
		)
		(fp_line
			(start 0.12065 -0.3048)
			(end 0.67945 -0.3048)
			(stroke
				(width 0.1)
				(type default)
			)
			(layer "F.Fab")
		)
		(fp_line
			(start 0.12065 -0.2794)
			(end 0.12065 -0.3048)
			(stroke
				(width 0.1)
				(type default)
			)
			(layer "F.Fab")
		)
		(fp_line
			(start -0.12065 -0.2794)
			(end 0.12065 -0.2794)
			(stroke
				(width 0.1)
				(type default)
			)
			(layer "F.Fab")
		)
		(fp_line
			(start 0.120396 0.2794)
			(end -0.12065 0.2794)
			(stroke
				(width 0.1)
				(type default)
			)
			(layer "F.Fab")
		)
		(fp_line
			(start -0.12065 0.2794)
			(end -0.12065 0.3048)
			(stroke
				(width 0.1)
				(type default)
			)
			(layer "F.Fab")
		)
		(fp_line
			(start 0.67945 0.3048)
			(end 0.120396 0.3048)
			(stroke
				(width 0.1)
				(type default)
			)
			(layer "F.Fab")
		)
		(fp_line
			(start 0.120396 0.3048)
			(end 0.120396 0.2794)
			(stroke
				(width 0.1)
				(type default)
			)
			(layer "F.Fab")
		)
		(fp_line
			(start -0.12065 0.3048)
			(end -0.67945 0.3048)
			(stroke
				(width 0.1)
				(type default)
			)
			(layer "F.Fab")
		)
		(fp_line
			(start -0.67945 0.3048)
			(end -0.67945 -0.305054)
			(stroke
				(width 0.1)
				(type default)
			)
			(layer "F.Fab")
		)
		(pad "1" smd circle
			(at -0.40005 0 90)
			(size 0 0)
			(layers "F.Cu" "F.Mask" "F.Paste")
			(net "PWRGD_P1V0_AUX_R")
		)
		(pad "2" smd circle
			(at 0.40005 0 90)
			(size 0 0)
			(layers "F.Cu" "F.Mask" "F.Paste")
			(net "PWRGD_P1V0_AUX")
		)
	)
)
